# S9S_MB_2U (Grand Teton) — schematic netlist excerpt (pin names and nets, part order shuffled) for the footprints in the layout excerpt that follows; sources: Cadence DE-HDL packaged netlist, KiCad conversion of 03242023_DA0F0TMBIJ0_F0T_Motherboard_J_brd_V01_OCP.brd

R805  Q_RES  33.2 1% CHIP  pkg 0402LF  page 221 : A = JTAG_PLD_TMS_R ; B = JTAG_BMC_PLD_TMS
R2236  Q_RES  100K 1% EMPTY  pkg 0402LF  page 306 : A = P12V_AUX ; B = A_HSC_INAP

(kicad_pcb
	(version 20260206)
	(generator "pcbnew")
	(generator_version "10.0")
	(general
		(thickness 1.6)
		(legacy_teardrops no)
	)
	(paper "A4")
	(title_block
		(title "03242023_DA0F0TMBIJ0_F0T_Motherboard_J_brd_V01_OCP.brd")
		(comment 1 "Grand Teton / footprints 3173-3174 of 6105")
	)
	(layers
		(0 "F.Cu" signal "TOP")
		(4 "In1.Cu" signal "GND")
		(6 "In2.Cu" signal "IN1")
		(8 "In3.Cu" signal "GND1")
		(10 "In4.Cu" signal "IN2")
		(12 "In5.Cu" signal "GND2")
		(14 "In6.Cu" signal "IN3")
		(16 "In7.Cu" signal "GND3")
		(18 "In8.Cu" signal "VCC")
		(20 "In9.Cu" signal "VCC1")
		(22 "In10.Cu" signal "GND4")
		(24 "In11.Cu" signal "IN4")
		(26 "In12.Cu" signal "GND5")
		(28 "In13.Cu" signal "IN5")
		(30 "In14.Cu" signal "GND6")
		(32 "In15.Cu" signal "IN6")
		(34 "In16.Cu" signal "GND7")
		(2 "B.Cu" signal "BOTTOM")
		(9 "F.Adhes" user "F.Adhesive")
		(11 "B.Adhes" user "B.Adhesive")
		(13 "F.Paste" user "Package Geometry/Pastemask Top")
		(15 "B.Paste" user "Package Geometry/Pastemask Bottom")
		(5 "F.SilkS" user "Ref Des/Silkscreen Top")
		(7 "B.SilkS" user "Ref Des/Silkscreen Bottom")
		(1 "F.Mask" user "Board Geometry/Soldermask Top")
		(3 "B.Mask" user "Board Geometry/Soldermask Bottom")
		(17 "Dwgs.User" user "User.Drawings")
		(19 "Cmts.User" user "User.Comments")
		(21 "Eco1.User" user "User.Eco1")
		(23 "Eco2.User" user "User.Eco2")
		(25 "Edge.Cuts" user "Board Geometry/Outline")
		(27 "Margin" user)
		(31 "F.CrtYd" user "Package Geometry/Place Bound Top")
		(29 "B.CrtYd" user "Package Geometry/Place Bound Bottom")
		(35 "F.Fab" user "Ref Des/Assembly Top")
		(33 "B.Fab" user "Ref Des/Assembly Bottom")
	)
	(footprint ""
		(layer "F.Cu")
		(at 220.100652 -105.226104 180)
		(property "Reference" "R2236"
			(at 0 0 180)
			(layer "F.SilkS")
			(hide yes)
			(effects
				(font
					(size 1.27 1.27)
				)
			)
		)
		(property "Value" ""
			(at 0 0 180)
			(layer "F.Fab")
			(effects
				(font
					(size 1.27 1.27)
				)
			)
		)
		(duplicate_pad_numbers_are_jumpers no)
		(fp_line
			(start 0.7874 0.4064)
			(end -0.7874 0.4064)
			(stroke
				(width 0.1524)
				(type default)
			)
			(layer "F.SilkS")
		)
		(fp_line
			(start 0.7874 -0.4064)
			(end 0.7874 0.4064)
			(stroke
				(width 0.1524)
				(type default)
			)
			(layer "F.SilkS")
		)
		(fp_line
			(start -0.7874 0.4064)
			(end -0.7874 -0.4064)
			(stroke
				(width 0.1524)
				(type default)
			)
			(layer "F.SilkS")
		)
		(fp_line
			(start -0.7874 -0.4064)
			(end 0.7874 -0.4064)
			(stroke
				(width 0.1524)
				(type default)
			)
			(layer "F.SilkS")
		)
		(fp_line
			(start 0.67945 0.3048)
			(end 0.120396 0.3048)
			(stroke
				(width 0.1)
				(type default)
			)
			(layer "F.Fab")
		)
		(fp_line
			(start 0.67945 -0.3048)
			(end 0.67945 0.3048)
			(stroke
				(width 0.1)
				(type default)
			)
			(layer "F.Fab")
		)
		(fp_line
			(start 0.12065 -0.2794)
			(end 0.12065 -0.3048)
			(stroke
				(width 0.1)
				(type default)
			)
			(layer "F.Fab")
		)
		(fp_line
			(start 0.12065 -0.3048)
			(end 0.67945 -0.3048)
			(stroke
				(width 0.1)
				(type default)
			)
			(layer "F.Fab")
		)
		(fp_line
			(start 0.120396 0.3048)
			(end 0.120396 0.2794)
			(stroke
				(width 0.1)
				(type default)
			)
			(layer "F.Fab")
		)
		(fp_line
			(start 0.120396 0.2794)
			(end -0.12065 0.2794)
			(stroke
				(width 0.1)
				(type default)
			)
			(layer "F.Fab")
		)
		(fp_line
			(start -0.12065 0.3048)
			(end -0.67945 0.3048)
			(stroke
				(width 0.1)
				(type default)
			)
			(layer "F.Fab")
		)
		(fp_line
			(start -0.12065 0.2794)
			(end -0.12065 0.3048)
			(stroke
				(width 0.1)
				(type default)
			)
			(layer "F.Fab")
		)
		(fp_line
			(start -0.12065 -0.2794)
			(end 0.12065 -0.2794)
			(stroke
				(width 0.1)
				(type default)
			)
			(layer "F.Fab")
		)
		(fp_line
			(start -0.12065 -0.305054)
			(end -0.12065 -0.2794)
			(stroke
				(width 0.1)
				(type default)
			)
			(layer "F.Fab")
		)
		(fp_line
			(start -0.67945 0.3048)
			(end -0.67945 -0.305054)
			(stroke
				(width 0.1)
				(type default)
			)
			(layer "F.Fab")
		)
		(fp_line
			(start -0.67945 -0.305054)
			(end -0.12065 -0.305054)
			(stroke
				(width 0.1)
				(type default)
			)
			(layer "F.Fab")
		)
		(pad "1" smd circle
			(at -0.40005 0 180)
			(size 0 0)
			(layers "F.Cu" "F.Mask" "F.Paste")
			(net "P12V_AUX")
		)
		(pad "2" smd circle
			(at 0.40005 0 180)
			(size 0 0)
			(layers "F.Cu" "F.Mask" "F.Paste")
			(net "A_HSC_INAP")
		)
	)
	(footprint ""
		(layer "F.Cu")
		(at 120.714008 -66.67754 90)
		(property "Reference" "R805"
			(at 0 0 90)
			(layer "F.SilkS")
			(hide yes)
			(effects
				(font
					(size 1.27 1.27)
				)
			)
		)
		(property "Value" ""
			(at 0 0 90)
			(layer "F.Fab")
			(effects
				(font
					(size 1.27 1.27)
				)
			)
		)
		(duplicate_pad_numbers_are_jumpers no)
		(fp_line
			(start 0.7874 -0.4064)
			(end 0.7874 0.4064)
			(stroke
				(width 0.1524)
				(type default)
			)
			(layer "F.SilkS")
		)
		(fp_line
			(start -0.7874 -0.4064)
			(end 0.7874 -0.4064)
			(stroke
				(width 0.1524)
				(type default)
			)
			(layer "F.SilkS")
		)
		(fp_line
			(start 0.7874 0.4064)
			(end -0.7874 0.4064)
			(stroke
				(width 0.1524)
				(type default)
			)
			(layer "F.SilkS")
		)
		(fp_line
			(start -0.7874 0.4064)
			(end -0.7874 -0.4064)
			(stroke
				(width 0.1524)
				(type default)
			)
			(layer "F.SilkS")
		)
		(fp_line
			(start -0.12065 -0.305054)
			(end -0.12065 -0.2794)
			(stroke
				(width 0.1)
				(type default)
			)
			(layer "F.Fab")
		)
		(fp_line
			(start -0.67945 -0.305054)
			(end -0.12065 -0.305054)
			(stroke
				(width 0.1)
				(type default)
			)
			(layer "F.Fab")
		)
		(fp_line
			(start 0.67945 -0.3048)
			(end 0.67945 0.3048)
			(stroke
				(width 0.1)
				(type default)
			)
			(layer "F.Fab")
		)
		(fp_line
			(start 0.12065 -0.3048)
			(end 0.67945 -0.3048)
			(stroke
				(width 0.1)
				(type default)
			)
			(layer "F.Fab")
		)
		(fp_line
			(start 0.12065 -0.2794)
			(end 0.12065 -0.3048)
			(stroke
				(width 0.1)
				(type default)
			)
			(layer "F.Fab")
		)
		(fp_line
			(start -0.12065 -0.2794)
			(end 0.12065 -0.2794)
			(stroke
				(width 0.1)
				(type default)
			)
			(layer "F.Fab")
		)
		(fp_line
			(start 0.120396 0.2794)
			(end -0.12065 0.2794)
			(stroke
				(width 0.1)
				(type default)
			)
			(layer "F.Fab")
		)
		(fp_line
			(start -0.12065 0.2794)
			(end -0.12065 0.3048)
			(stroke
				(width 0.1)
				(type default)
			)
			(layer "F.Fab")
		)
		(fp_line
			(start 0.67945 0.3048)
			(end 0.120396 0.3048)
			(stroke
				(width 0.1)
				(type default)
			)
			(layer "F.Fab")
		)
		(fp_line
			(start 0.120396 0.3048)
			(end 0.120396 0.2794)
			(stroke
				(width 0.1)
				(type default)
			)
			(layer "F.Fab")
		)
		(fp_line
			(start -0.12065 0.3048)
			(end -0.67945 0.3048)
			(stroke
				(width 0.1)
				(type default)
			)
			(layer "F.Fab")
		)
		(fp_line
			(start -0.67945 0.3048)
			(end -0.67945 -0.305054)
			(stroke
				(width 0.1)
				(type default)
			)
			(layer "F.Fab")
		)
		(pad "1" smd circle
			(at -0.40005 0 90)
			(size 0 0)
			(layers "F.Cu" "F.Mask" "F.Paste")
			(net "JTAG_PLD_TMS_R")
		)
		(pad "2" smd circle
			(at 0.40005 0 90)
			(size 0 0)
			(layers "F.Cu" "F.Mask" "F.Paste")
			(net "JTAG_BMC_PLD_TMS")
		)
	)
)
